# SCM (Grand Teton) — schematic netlist excerpt (pin names and nets, part order shuffled) for the footprints in the layout excerpt that follows; sources: Cadence DE-HDL packaged netlist, KiCad conversion of 12092022_DA0F0TMDCD0_F0T_Management_Board_D_brd_V3_OCP.brd

PC215  Q_CAP  22UF 10V 20% X6S  pkg C0805  page 51 : A = P5V_AUX ; B = GND
C310  Q_CAP  1UF 25V 10% X6S  pkg C0402  page 54 : A = PWRGD_P3V3_RGM_R2 ; B = GND
R181  Q_RES  4.7K 1% CHIP  pkg 0402LF  page 25 : A = P3V3_AUX ; B = FM_FLASH_LATCH_N

(kicad_pcb
	(version 20260206)
	(generator "pcbnew")
	(generator_version "10.0")
	(general
		(thickness 1.6)
		(legacy_teardrops no)
	)
	(paper "A4")
	(title_block
		(title "12092022_DA0F0TMDCD0_F0T_Management_Board_D_brd_V3_OCP.brd")
		(comment 1 "Grand Teton / footprints 173-175 of 1440")
	)
	(layers
		(0 "F.Cu" signal "TOP")
		(4 "In1.Cu" signal "GND")
		(6 "In2.Cu" signal "IN1")
		(8 "In3.Cu" signal "GND1")
		(10 "In4.Cu" signal "IN2")
		(12 "In5.Cu" signal "VCC")
		(14 "In6.Cu" signal "VCC1")
		(16 "In7.Cu" signal "IN3")
		(18 "In8.Cu" signal "GND2")
		(20 "In9.Cu" signal "IN4")
		(22 "In10.Cu" signal "GND3")
		(2 "B.Cu" signal "BOTTOM")
		(9 "F.Adhes" user "F.Adhesive")
		(11 "B.Adhes" user "B.Adhesive")
		(13 "F.Paste" user "Package Geometry/Pastemask Top")
		(15 "B.Paste" user "Package Geometry/Pastemask Bottom")
		(5 "F.SilkS" user "Ref Des/Silkscreen Top")
		(7 "B.SilkS" user "Ref Des/Silkscreen Bottom")
		(1 "F.Mask" user "Board Geometry/Soldermask Top")
		(3 "B.Mask" user "Board Geometry/Soldermask Bottom")
		(17 "Dwgs.User" user "User.Drawings")
		(19 "Cmts.User" user "User.Comments")
		(21 "Eco1.User" user "User.Eco1")
		(23 "Eco2.User" user "User.Eco2")
		(25 "Edge.Cuts" user "Board Geometry/Outline")
		(27 "Margin" user)
		(31 "F.CrtYd" user "Package Geometry/Place Bound Top")
		(29 "B.CrtYd" user "Package Geometry/Place Bound Bottom")
		(35 "F.Fab" user "Ref Des/Assembly Top")
		(33 "B.Fab" user "Ref Des/Assembly Bottom")
	)
	(footprint ""
		(layer "F.Cu")
		(at 46.9646 -76.2508)
		(property "Reference" "R181"
			(at 0 0 0)
			(layer "F.SilkS")
			(hide yes)
			(effects
				(font
					(size 1.27 1.27)
				)
			)
		)
		(property "Value" ""
			(at 0 0 0)
			(layer "F.Fab")
			(effects
				(font
					(size 1.27 1.27)
				)
			)
		)
		(duplicate_pad_numbers_are_jumpers no)
		(fp_line
			(start -0.7874 -0.4064)
			(end 0.7874 -0.4064)
			(stroke
				(width 0.1524)
				(type default)
			)
			(layer "F.SilkS")
		)
		(fp_line
			(start -0.7874 0.4064)
			(end -0.7874 -0.4064)
			(stroke
				(width 0.1524)
				(type default)
			)
			(layer "F.SilkS")
		)
		(fp_line
			(start 0.7874 -0.4064)
			(end 0.7874 0.4064)
			(stroke
				(width 0.1524)
				(type default)
			)
			(layer "F.SilkS")
		)
		(fp_line
			(start 0.7874 0.4064)
			(end -0.7874 0.4064)
			(stroke
				(width 0.1524)
				(type default)
			)
			(layer "F.SilkS")
		)
		(fp_line
			(start -0.67945 -0.305054)
			(end -0.12065 -0.305054)
			(stroke
				(width 0.1)
				(type default)
			)
			(layer "F.Fab")
		)
		(fp_line
			(start -0.67945 0.3048)
			(end -0.67945 -0.305054)
			(stroke
				(width 0.1)
				(type default)
			)
			(layer "F.Fab")
		)
		(fp_line
			(start -0.12065 -0.305054)
			(end -0.12065 -0.2794)
			(stroke
				(width 0.1)
				(type default)
			)
			(layer "F.Fab")
		)
		(fp_line
			(start -0.12065 -0.2794)
			(end 0.12065 -0.2794)
			(stroke
				(width 0.1)
				(type default)
			)
			(layer "F.Fab")
		)
		(fp_line
			(start -0.12065 0.2794)
			(end -0.12065 0.3048)
			(stroke
				(width 0.1)
				(type default)
			)
			(layer "F.Fab")
		)
		(fp_line
			(start -0.12065 0.3048)
			(end -0.67945 0.3048)
			(stroke
				(width 0.1)
				(type default)
			)
			(layer "F.Fab")
		)
		(fp_line
			(start 0.120396 0.2794)
			(end -0.12065 0.2794)
			(stroke
				(width 0.1)
				(type default)
			)
			(layer "F.Fab")
		)
		(fp_line
			(start 0.120396 0.3048)
			(end 0.120396 0.2794)
			(stroke
				(width 0.1)
				(type default)
			)
			(layer "F.Fab")
		)
		(fp_line
			(start 0.12065 -0.3048)
			(end 0.67945 -0.3048)
			(stroke
				(width 0.1)
				(type default)
			)
			(layer "F.Fab")
		)
		(fp_line
			(start 0.12065 -0.2794)
			(end 0.12065 -0.3048)
			(stroke
				(width 0.1)
				(type default)
			)
			(layer "F.Fab")
		)
		(fp_line
			(start 0.67945 -0.3048)
			(end 0.67945 0.3048)
			(stroke
				(width 0.1)
				(type default)
			)
			(layer "F.Fab")
		)
		(fp_line
			(start 0.67945 0.3048)
			(end 0.120396 0.3048)
			(stroke
				(width 0.1)
				(type default)
			)
			(layer "F.Fab")
		)
		(pad "1" smd circle
			(at -0.40005 0)
			(size 0 0)
			(layers "F.Cu" "F.Mask" "F.Paste")
			(net "P3V3_AUX")
		)
		(pad "2" smd circle
			(at 0.40005 0)
			(size 0 0)
			(layers "F.Cu" "F.Mask" "F.Paste")
			(net "FM_FLASH_LATCH_N")
		)
	)
	(footprint ""
		(layer "F.Cu")
		(at 32.131 -64.8208 90)
		(property "Reference" "C310"
			(at 0 0 90)
			(layer "F.SilkS")
			(hide yes)
			(effects
				(font
					(size 1.27 1.27)
				)
			)
		)
		(property "Value" ""
			(at 0 0 90)
			(layer "F.Fab")
			(effects
				(font
					(size 1.27 1.27)
				)
			)
		)
		(duplicate_pad_numbers_are_jumpers no)
		(fp_line
			(start 0.7874 -0.4064)
			(end 0.7874 0.4064)
			(stroke
				(width 0.1524)
				(type default)
			)
			(layer "F.SilkS")
		)
		(fp_line
			(start -0.7874 -0.4064)
			(end 0.7874 -0.4064)
			(stroke
				(width 0.1524)
				(type default)
			)
			(layer "F.SilkS")
		)
		(fp_line
			(start 0.7874 0.4064)
			(end -0.7874 0.4064)
			(stroke
				(width 0.1524)
				(type default)
			)
			(layer "F.SilkS")
		)
		(fp_line
			(start -0.7874 0.4064)
			(end -0.7874 -0.4064)
			(stroke
				(width 0.1524)
				(type default)
			)
			(layer "F.SilkS")
		)
		(fp_line
			(start -0.12065 -0.305054)
			(end -0.12065 -0.2794)
			(stroke
				(width 0.1)
				(type default)
			)
			(layer "F.Fab")
		)
		(fp_line
			(start -0.67945 -0.305054)
			(end -0.12065 -0.305054)
			(stroke
				(width 0.1)
				(type default)
			)
			(layer "F.Fab")
		)
		(fp_line
			(start 0.67945 -0.3048)
			(end 0.67945 0.3048)
			(stroke
				(width 0.1)
				(type default)
			)
			(layer "F.Fab")
		)
		(fp_line
			(start 0.12065 -0.3048)
			(end 0.67945 -0.3048)
			(stroke
				(width 0.1)
				(type default)
			)
			(layer "F.Fab")
		)
		(fp_line
			(start 0.12065 -0.2794)
			(end 0.12065 -0.3048)
			(stroke
				(width 0.1)
				(type default)
			)
			(layer "F.Fab")
		)
		(fp_line
			(start -0.12065 -0.2794)
			(end 0.12065 -0.2794)
			(stroke
				(width 0.1)
				(type default)
			)
			(layer "F.Fab")
		)
		(fp_line
			(start 0.120396 0.2794)
			(end -0.12065 0.2794)
			(stroke
				(width 0.1)
				(type default)
			)
			(layer "F.Fab")
		)
		(fp_line
			(start -0.12065 0.2794)
			(end -0.12065 0.3048)
			(stroke
				(width 0.1)
				(type default)
			)
			(layer "F.Fab")
		)
		(fp_line
			(start 0.67945 0.3048)
			(end 0.120396 0.3048)
			(stroke
				(width 0.1)
				(type default)
			)
			(layer "F.Fab")
		)
		(fp_line
			(start 0.120396 0.3048)
			(end 0.120396 0.2794)
			(stroke
				(width 0.1)
				(type default)
			)
			(layer "F.Fab")
		)
		(fp_line
			(start -0.12065 0.3048)
			(end -0.67945 0.3048)
			(stroke
				(width 0.1)
				(type default)
			)
			(layer "F.Fab")
		)
		(fp_line
			(start -0.67945 0.3048)
			(end -0.67945 -0.305054)
			(stroke
				(width 0.1)
				(type default)
			)
			(layer "F.Fab")
		)
		(pad "1" smd circle
			(at -0.40005 0 90)
			(size 0 0)
			(layers "F.Cu" "F.Mask" "F.Paste")
			(net "PWRGD_P3V3_RGM_R2")
		)
		(pad "2" smd circle
			(at 0.40005 0 90)
			(size 0 0)
			(layers "F.Cu" "F.Mask" "F.Paste")
			(net "GND")
		)
	)
	(footprint ""
		(layer "F.Cu")
		(at 4.953 -31.837122 -90)
		(property "Reference" "PC215"
			(at 0 0 270)
			(layer "F.SilkS")
			(hide yes)
			(effects
				(font
					(size 1.27 1.27)
				)
			)
		)
		(property "Value" ""
			(at 0 0 270)
			(layer "F.Fab")
			(effects
				(font
					(size 1.27 1.27)
				)
			)
		)
		(duplicate_pad_numbers_are_jumpers no)
		(fp_line
			(start -1.651 0.8382)
			(end -1.651 -0.8382)
			(stroke
				(width 0.1524)
				(type default)
			)
			(layer "F.SilkS")
		)
		(fp_line
			(start 0 0.8382)
			(end 0 -0.8382)
			(stroke
				(width 0.1524)
				(type default)
			)
			(layer "F.SilkS")
		)
		(fp_line
			(start 1.651 0.8382)
			(end -1.651 0.8382)
			(stroke
				(width 0.1524)
				(type default)
			)
			(layer "F.SilkS")
		)
		(fp_line
			(start -1.651 -0.8382)
			(end 1.651 -0.8382)
			(stroke
				(width 0.1524)
				(type default)
			)
			(layer "F.SilkS")
		)
		(fp_line
			(start 1.651 -0.8382)
			(end 1.651 0.8382)
			(stroke
				(width 0.1524)
				(type default)
			)
			(layer "F.SilkS")
		)
		(fp_line
			(start -1.55956 0.7366)
			(end -1.524 0.7366)
			(stroke
				(width 0.1)
				(type default)
			)
			(layer "F.Fab")
		)
		(fp_line
			(start -1.524 0.7366)
			(end 1.524 0.7366)
			(stroke
				(width 0.1)
				(type default)
			)
			(layer "F.Fab")
		)
		(fp_line
			(start 1.524 0.7366)
			(end 1.55956 0.7366)
			(stroke
				(width 0.1)
				(type default)
			)
			(layer "F.Fab")
		)
		(fp_line
			(start 1.55956 0.7366)
			(end 1.55956 -0.7366)
			(stroke
				(width 0.1)
				(type default)
			)
			(layer "F.Fab")
		)
		(fp_line
			(start -1.55956 -0.7366)
			(end -1.55956 0.7366)
			(stroke
				(width 0.1)
				(type default)
			)
			(layer "F.Fab")
		)
		(fp_line
			(start -1.524 -0.7366)
			(end -1.55956 -0.7366)
			(stroke
				(width 0.1)
				(type default)
			)
			(layer "F.Fab")
		)
		(fp_line
			(start 1.524 -0.7366)
			(end -1.524 -0.7366)
			(stroke
				(width 0.1)
				(type default)
			)
			(layer "F.Fab")
		)
		(fp_line
			(start 1.55956 -0.7366)
			(end 1.524 -0.7366)
			(stroke
				(width 0.1)
				(type default)
			)
			(layer "F.Fab")
		)
		(pad "1" smd rect
			(at -0.94996 0 90)
			(size 1.1176 1.3716)
			(layers "F.Cu" "F.Mask" "F.Paste")
			(net "P5V_AUX")
		)
		(pad "2" smd rect
			(at 0.94996 0 90)
			(size 1.1176 1.3716)
			(layers "F.Cu" "F.Mask" "F.Paste")
			(net "GND")
		)
	)
)
